# T6G (Grand Teton) — schematic netlist excerpt (pin names and nets, part order shuffled) for the footprints in the layout excerpt that follows; sources: Cadence DE-HDL packaged netlist, KiCad conversion of 04192023_DAF0TMB3IC0_F0TG_MB_C_brd_V02_OCP.brd

R9276  Q_RES  0 5% CHIP  pkg 0402LF  page 28 : A = CLK_100M_CPU0_CLK05_R_DN ; B = CLK_100M_CPU0_CLK05_DN
R456  Q_RES  4.7K 5% EMPTY  pkg 0402LF  page 55 : A = CPU1_PWRGD_OUT ; B = PVDD18_S5_P1

(kicad_pcb
	(version 20260206)
	(generator "pcbnew")
	(generator_version "10.0")
	(general
		(thickness 1.6)
		(legacy_teardrops no)
	)
	(paper "A4")
	(title_block
		(title "04192023_DAF0TMB3IC0_F0TG_MB_C_brd_V02_OCP.brd")
		(comment 1 "Grand Teton / footprints 6612-6613 of 8354")
	)
	(layers
		(0 "F.Cu" signal "TOP")
		(4 "In1.Cu" signal "GND")
		(6 "In2.Cu" signal "IN1")
		(8 "In3.Cu" signal "GND1")
		(10 "In4.Cu" signal "IN2")
		(12 "In5.Cu" signal "GND2")
		(14 "In6.Cu" signal "IN3")
		(16 "In7.Cu" signal "GND3")
		(18 "In8.Cu" signal "VCC")
		(20 "In9.Cu" signal "VCC1")
		(22 "In10.Cu" signal "GND4")
		(24 "In11.Cu" signal "IN4")
		(26 "In12.Cu" signal "GND5")
		(28 "In13.Cu" signal "IN5")
		(30 "In14.Cu" signal "GND6")
		(32 "In15.Cu" signal "IN6")
		(34 "In16.Cu" signal "GND7")
		(2 "B.Cu" signal "BOTTOM")
		(9 "F.Adhes" user "F.Adhesive")
		(11 "B.Adhes" user "B.Adhesive")
		(13 "F.Paste" user "Package Geometry/Pastemask Top")
		(15 "B.Paste" user "Package Geometry/Pastemask Bottom")
		(5 "F.SilkS" user "Ref Des/Silkscreen Top")
		(7 "B.SilkS" user "Ref Des/Silkscreen Bottom")
		(1 "F.Mask" user "Board Geometry/Soldermask Top")
		(3 "B.Mask" user "Board Geometry/Soldermask Bottom")
		(17 "Dwgs.User" user "User.Drawings")
		(19 "Cmts.User" user "User.Comments")
		(21 "Eco1.User" user "User.Eco1")
		(23 "Eco2.User" user "User.Eco2")
		(25 "Edge.Cuts" user "Board Geometry/Outline")
		(27 "Margin" user)
		(31 "F.CrtYd" user "Package Geometry/Place Bound Top")
		(29 "B.CrtYd" user "Package Geometry/Place Bound Bottom")
		(35 "F.Fab" user "Ref Des/Assembly Top")
		(33 "B.Fab" user "Ref Des/Assembly Bottom")
	)
	(footprint ""
		(layer "B.Cu")
		(at 94.460314 -306.714652)
		(property "Reference" "R456"
			(at 0 0 0)
			(layer "B.SilkS")
			(hide yes)
			(effects
				(font
					(size 1.27 1.27)
				)
				(justify mirror)
			)
		)
		(property "Value" ""
			(at 0 0 0)
			(layer "B.Fab")
			(effects
				(font
					(size 1.27 1.27)
				)
				(justify mirror)
			)
		)
		(duplicate_pad_numbers_are_jumpers no)
		(fp_line
			(start -0.7874 -0.4064)
			(end -0.7874 0.4064)
			(stroke
				(width 0.1524)
				(type default)
			)
			(layer "B.SilkS")
		)
		(fp_line
			(start -0.7874 0.4064)
			(end 0.7874 0.4064)
			(stroke
				(width 0.1524)
				(type default)
			)
			(layer "B.SilkS")
		)
		(fp_line
			(start 0.7874 -0.4064)
			(end -0.7874 -0.4064)
			(stroke
				(width 0.1524)
				(type default)
			)
			(layer "B.SilkS")
		)
		(fp_line
			(start 0.7874 0.4064)
			(end 0.7874 -0.4064)
			(stroke
				(width 0.1524)
				(type default)
			)
			(layer "B.SilkS")
		)
		(fp_line
			(start -0.67945 -0.3048)
			(end -0.67945 0.3048)
			(stroke
				(width 0.1)
				(type default)
			)
			(layer "B.Fab")
		)
		(fp_line
			(start -0.67945 0.3048)
			(end -0.120396 0.3048)
			(stroke
				(width 0.1)
				(type default)
			)
			(layer "B.Fab")
		)
		(fp_line
			(start -0.12065 -0.3048)
			(end -0.67945 -0.3048)
			(stroke
				(width 0.1)
				(type default)
			)
			(layer "B.Fab")
		)
		(fp_line
			(start -0.12065 -0.2794)
			(end -0.12065 -0.3048)
			(stroke
				(width 0.1)
				(type default)
			)
			(layer "B.Fab")
		)
		(fp_line
			(start -0.120396 0.2794)
			(end 0.12065 0.2794)
			(stroke
				(width 0.1)
				(type default)
			)
			(layer "B.Fab")
		)
		(fp_line
			(start -0.120396 0.3048)
			(end -0.120396 0.2794)
			(stroke
				(width 0.1)
				(type default)
			)
			(layer "B.Fab")
		)
		(fp_line
			(start 0.12065 -0.305054)
			(end 0.12065 -0.2794)
			(stroke
				(width 0.1)
				(type default)
			)
			(layer "B.Fab")
		)
		(fp_line
			(start 0.12065 -0.2794)
			(end -0.12065 -0.2794)
			(stroke
				(width 0.1)
				(type default)
			)
			(layer "B.Fab")
		)
		(fp_line
			(start 0.12065 0.2794)
			(end 0.12065 0.3048)
			(stroke
				(width 0.1)
				(type default)
			)
			(layer "B.Fab")
		)
		(fp_line
			(start 0.12065 0.3048)
			(end 0.67945 0.3048)
			(stroke
				(width 0.1)
				(type default)
			)
			(layer "B.Fab")
		)
		(fp_line
			(start 0.67945 -0.305054)
			(end 0.12065 -0.305054)
			(stroke
				(width 0.1)
				(type default)
			)
			(layer "B.Fab")
		)
		(fp_line
			(start 0.67945 0.3048)
			(end 0.67945 -0.305054)
			(stroke
				(width 0.1)
				(type default)
			)
			(layer "B.Fab")
		)
		(pad "1" smd circle
			(at 0.40005 0 180)
			(size 0 0)
			(layers "B.Cu" "B.Mask" "B.Paste")
			(net "CPU1_PWRGD_OUT")
		)
		(pad "2" smd circle
			(at -0.40005 0 180)
			(size 0 0)
			(layers "B.Cu" "B.Mask" "B.Paste")
			(net "PVDD18_S5_P1")
		)
	)
	(footprint ""
		(layer "B.Cu")
		(at 377.839986 -214.523828 90)
		(property "Reference" "R9276"
			(at 0 0 90)
			(layer "B.SilkS")
			(hide yes)
			(effects
				(font
					(size 1.27 1.27)
				)
				(justify mirror)
			)
		)
		(property "Value" ""
			(at 0 0 90)
			(layer "B.Fab")
			(effects
				(font
					(size 1.27 1.27)
				)
				(justify mirror)
			)
		)
		(duplicate_pad_numbers_are_jumpers no)
		(fp_line
			(start 0.7874 -0.4064)
			(end -0.7874 -0.4064)
			(stroke
				(width 0.1524)
				(type default)
			)
			(layer "B.SilkS")
		)
		(fp_line
			(start -0.7874 -0.4064)
			(end -0.7874 0.086614)
			(stroke
				(width 0.1524)
				(type default)
			)
			(layer "B.SilkS")
		)
		(fp_line
			(start 0.7874 0.035814)
			(end 0.7874 -0.4064)
			(stroke
				(width 0.1524)
				(type default)
			)
			(layer "B.SilkS")
		)
		(fp_line
			(start -0.376428 0.4064)
			(end 0.360172 0.4064)
			(stroke
				(width 0.1524)
				(type default)
			)
			(layer "B.SilkS")
		)
		(fp_line
			(start 0.67945 -0.305054)
			(end 0.12065 -0.305054)
			(stroke
				(width 0.1)
				(type default)
			)
			(layer "B.Fab")
		)
		(fp_line
			(start 0.12065 -0.305054)
			(end 0.12065 -0.2794)
			(stroke
				(width 0.1)
				(type default)
			)
			(layer "B.Fab")
		)
		(fp_line
			(start -0.12065 -0.3048)
			(end -0.67945 -0.3048)
			(stroke
				(width 0.1)
				(type default)
			)
			(layer "B.Fab")
		)
		(fp_line
			(start -0.67945 -0.3048)
			(end -0.67945 0.3048)
			(stroke
				(width 0.1)
				(type default)
			)
			(layer "B.Fab")
		)
		(fp_line
			(start 0.12065 -0.2794)
			(end -0.12065 -0.2794)
			(stroke
				(width 0.1)
				(type default)
			)
			(layer "B.Fab")
		)
		(fp_line
			(start -0.12065 -0.2794)
			(end -0.12065 -0.3048)
			(stroke
				(width 0.1)
				(type default)
			)
			(layer "B.Fab")
		)
		(fp_line
			(start 0.12065 0.2794)
			(end 0.12065 0.3048)
			(stroke
				(width 0.1)
				(type default)
			)
			(layer "B.Fab")
		)
		(fp_line
			(start -0.120396 0.2794)
			(end 0.12065 0.2794)
			(stroke
				(width 0.1)
				(type default)
			)
			(layer "B.Fab")
		)
		(fp_line
			(start 0.67945 0.3048)
			(end 0.67945 -0.305054)
			(stroke
				(width 0.1)
				(type default)
			)
			(layer "B.Fab")
		)
		(fp_line
			(start 0.12065 0.3048)
			(end 0.67945 0.3048)
			(stroke
				(width 0.1)
				(type default)
			)
			(layer "B.Fab")
		)
		(fp_line
			(start -0.120396 0.3048)
			(end -0.120396 0.2794)
			(stroke
				(width 0.1)
				(type default)
			)
			(layer "B.Fab")
		)
		(fp_line
			(start -0.67945 0.3048)
			(end -0.120396 0.3048)
			(stroke
				(width 0.1)
				(type default)
			)
			(layer "B.Fab")
		)
		(pad "1" smd circle
			(at 0.40005 0 270)
			(size 0 0)
			(layers "B.Cu" "B.Mask" "B.Paste")
			(net "CLK_100M_CPU0_CLK05_R_DN")
		)
		(pad "2" smd circle
			(at -0.40005 0 270)
			(size 0 0)
			(layers "B.Cu" "B.Mask" "B.Paste")
			(net "CLK_100M_CPU0_CLK05_DN")
		)
	)
)
